(kicad_pcb
	(version 20260206)
	(generator "pcbnew")
	(generator_version "10.0")
	(general
		(thickness 1.6)
		(legacy_teardrops no)
	)
	(paper "A4")
	(title_block
		(title "Bryce Canyon_SCC_16316-1_OCP.brd")
		(comment 1 "Bryce Canyon / footprints 1151-1158 of 1561")
	)
	(layers
		(0 "F.Cu" signal "TOP")
		(4 "In1.Cu" signal "L2GND")
		(6 "In2.Cu" signal "L3")
		(8 "In3.Cu" signal "L4VCC")
		(10 "In4.Cu" signal "L5VCC")
		(12 "In5.Cu" signal "L6")
		(14 "In6.Cu" signal "L7GND")
		(2 "B.Cu" signal "BOTTOM")
		(9 "F.Adhes" user "F.Adhesive")
		(11 "B.Adhes" user "B.Adhesive")
		(13 "F.Paste" user "Package Geometry/Pastemask Top")
		(15 "B.Paste" user "Package Geometry/Pastemask Bottom")
		(5 "F.SilkS" user "Ref Des/Silkscreen Top")
		(7 "B.SilkS" user "Ref Des/Silkscreen Bottom")
		(1 "F.Mask" user "Board Geometry/Soldermask Top")
		(3 "B.Mask" user "Board Geometry/Soldermask Bottom")
		(17 "Dwgs.User" user "User.Drawings")
		(19 "Cmts.User" user "User.Comments")
		(21 "Eco1.User" user "User.Eco1")
		(23 "Eco2.User" user "User.Eco2")
		(25 "Edge.Cuts" user "Board Geometry/Outline")
		(27 "Margin" user)
		(31 "F.CrtYd" user "Package Geometry/Place Bound Top")
		(29 "B.CrtYd" user "Package Geometry/Place Bound Bottom")
		(35 "F.Fab" user "Ref Des/Assembly Top")
		(33 "B.Fab" user "Ref Des/Assembly Bottom")
	)
	(footprint ""
		(layer "B.Cu")
		(at 131.6736 -116.0272 -90)
		(property "Reference" "C689"
			(at 0 0 90)
			(layer "B.SilkS")
			(hide yes)
			(effects
				(font
					(size 1.27 1.27)
				)
				(justify mirror)
			)
		)
		(property "Value" "SCD1U16V2KX-3GP"
			(at -1.1811 -2.7051 270)
			(unlocked yes)
			(layer "B.Fab")
			(hide yes)
			(effects
				(font
					(size 1.016 1.016)
					(thickness 0.1524)
				)
				(justify mirror)
			)
		)
		(property "Device Type" "C402H22"
			(at -1.1811 -4.2291 270)
			(unlocked yes)
			(layer "B.Fab")
			(hide yes)
			(effects
				(font
					(size 1.016 1.016)
					(thickness 0.1524)
				)
				(justify mirror)
			)
		)
		(duplicate_pad_numbers_are_jumpers no)
		(fp_rect
			(start 0.4318 0.9525)
			(end -0.4318 -0.9525)
			(stroke
				(width 0)
				(type default)
			)
			(fill no)
			(layer "B.CrtYd")
		)
		(fp_rect
			(start 0.4318 0.9525)
			(end -0.4318 -0.9525)
			(stroke
				(width 0)
				(type default)
			)
			(fill no)
			(layer "B.Fab")
		)
		(pad "1" smd custom
			(at 0 -0.4445 90)
			(size 0.1524 0.1524)
			(layers "B.Cu" "B.Mask" "B.Paste")
			(net "P1V5_C")
			(options
				(clearance outline)
				(anchor circle)
			)
			(primitives
				(gr_poly
					(pts
						(arc
							(start 0.3048 0.2032)
							(mid 0.275042 0.275042)
							(end 0.2032 0.3048)
						)
						(arc
							(start -0.2032 0.3048)
							(mid -0.275042 0.275042)
							(end -0.3048 0.2032)
						)
						(arc
							(start -0.3048 -0.2032)
							(mid -0.275042 -0.275042)
							(end -0.2032 -0.3048)
						)
						(arc
							(start 0.2032 -0.3048)
							(mid 0.275042 -0.275042)
							(end 0.3048 -0.2032)
						)
					)
					(width 0)
					(fill yes)
				)
			)
		)
		(pad "2" smd custom
			(at 0 0.4445 90)
			(size 0.1524 0.1524)
			(layers "B.Cu" "B.Mask" "B.Paste")
			(net "GND")
			(options
				(clearance outline)
				(anchor circle)
			)
			(primitives
				(gr_poly
					(pts
						(arc
							(start 0.3048 0.2032)
							(mid 0.275042 0.275042)
							(end 0.2032 0.3048)
						)
						(arc
							(start -0.2032 0.3048)
							(mid -0.275042 0.275042)
							(end -0.3048 0.2032)
						)
						(arc
							(start -0.3048 -0.2032)
							(mid -0.275042 -0.275042)
							(end -0.2032 -0.3048)
						)
						(arc
							(start 0.2032 -0.3048)
							(mid 0.275042 -0.275042)
							(end 0.3048 -0.2032)
						)
					)
					(width 0)
					(fill yes)
				)
			)
		)
	)
	(footprint ""
		(layer "B.Cu")
		(at 122.4788 -71.5137 -90)
		(property "Reference" "C531"
			(at 0 0 90)
			(layer "B.SilkS")
			(hide yes)
			(effects
				(font
					(size 1.27 1.27)
				)
				(justify mirror)
			)
		)
		(property "Value" "SCD1U6D3V1KX-GP"
			(at 2.8321 -1.7399 270)
			(unlocked yes)
			(layer "B.Fab")
			(hide yes)
			(effects
				(font
					(size 1.016 1.016)
					(thickness 0.1524)
				)
				(justify mirror)
			)
		)
		(property "Device Type" "C0201H13"
			(at 2.8321 -3.2639 270)
			(unlocked yes)
			(layer "B.Fab")
			(hide yes)
			(effects
				(font
					(size 1.016 1.016)
					(thickness 0.1524)
				)
				(justify mirror)
			)
		)
		(duplicate_pad_numbers_are_jumpers no)
		(fp_rect
			(start 0.2794 0.6477)
			(end -0.2794 -0.6477)
			(stroke
				(width 0)
				(type default)
			)
			(fill no)
			(layer "B.CrtYd")
		)
		(fp_rect
			(start 0.2794 0.6477)
			(end -0.2794 -0.6477)
			(stroke
				(width 0)
				(type default)
			)
			(fill no)
			(layer "B.Fab")
		)
		(pad "1" smd custom
			(at 0 -0.2794 90)
			(size 0.0762 0.0762)
			(layers "B.Cu" "B.Mask" "B.Paste")
			(net "GB_VDDA")
			(options
				(clearance outline)
				(anchor circle)
			)
			(primitives
				(gr_poly
					(pts
						(arc
							(start 0.1524 0.127)
							(mid 0.137521 0.162921)
							(end 0.1016 0.1778)
						)
						(arc
							(start -0.1016 0.1778)
							(mid -0.137521 0.162921)
							(end -0.1524 0.127)
						)
						(arc
							(start -0.1524 -0.127)
							(mid -0.137521 -0.162921)
							(end -0.1016 -0.1778)
						)
						(arc
							(start 0.1016 -0.1778)
							(mid 0.137521 -0.162921)
							(end 0.1524 -0.127)
						)
					)
					(width 0)
					(fill yes)
				)
			)
		)
		(pad "2" smd custom
			(at 0 0.2794 90)
			(size 0.0762 0.0762)
			(layers "B.Cu" "B.Mask" "B.Paste")
			(net "GND")
			(options
				(clearance outline)
				(anchor circle)
			)
			(primitives
				(gr_poly
					(pts
						(arc
							(start 0.1524 0.127)
							(mid 0.137521 0.162921)
							(end 0.1016 0.1778)
						)
						(arc
							(start -0.1016 0.1778)
							(mid -0.137521 0.162921)
							(end -0.1524 0.127)
						)
						(arc
							(start -0.1524 -0.127)
							(mid -0.137521 -0.162921)
							(end -0.1016 -0.1778)
						)
						(arc
							(start 0.1016 -0.1778)
							(mid 0.137521 -0.162921)
							(end 0.1524 -0.127)
						)
					)
					(width 0)
					(fill yes)
				)
			)
		)
	)
	(footprint ""
		(layer "B.Cu")
		(at 183.144668 -36.87191 -90)
		(property "Reference" "C474"
			(at 0 0 90)
			(layer "B.SilkS")
			(hide yes)
			(effects
				(font
					(size 1.27 1.27)
				)
				(justify mirror)
			)
		)
		(property "Value" "SCD1U6D3V1KX-GP"
			(at 2.8321 -1.7399 270)
			(unlocked yes)
			(layer "B.Fab")
			(hide yes)
			(effects
				(font
					(size 1.016 1.016)
					(thickness 0.1524)
				)
				(justify mirror)
			)
		)
		(property "Device Type" "C0201H13"
			(at 2.8321 -3.2639 270)
			(unlocked yes)
			(layer "B.Fab")
			(hide yes)
			(effects
				(font
					(size 1.016 1.016)
					(thickness 0.1524)
				)
				(justify mirror)
			)
		)
		(duplicate_pad_numbers_are_jumpers no)
		(fp_rect
			(start 0.2794 0.6477)
			(end -0.2794 -0.6477)
			(stroke
				(width 0)
				(type default)
			)
			(fill no)
			(layer "B.CrtYd")
		)
		(fp_rect
			(start 0.2794 0.6477)
			(end -0.2794 -0.6477)
			(stroke
				(width 0)
				(type default)
			)
			(fill no)
			(layer "B.Fab")
		)
		(pad "1" smd custom
			(at 0 -0.2794 90)
			(size 0.0762 0.0762)
			(layers "B.Cu" "B.Mask" "B.Paste")
			(net "P1V8_C")
			(options
				(clearance outline)
				(anchor circle)
			)
			(primitives
				(gr_poly
					(pts
						(arc
							(start 0.1524 0.127)
							(mid 0.137521 0.162921)
							(end 0.1016 0.1778)
						)
						(arc
							(start -0.1016 0.1778)
							(mid -0.137521 0.162921)
							(end -0.1524 0.127)
						)
						(arc
							(start -0.1524 -0.127)
							(mid -0.137521 -0.162921)
							(end -0.1016 -0.1778)
						)
						(arc
							(start 0.1016 -0.1778)
							(mid 0.137521 -0.162921)
							(end 0.1524 -0.127)
						)
					)
					(width 0)
					(fill yes)
				)
			)
		)
		(pad "2" smd custom
			(at 0 0.2794 90)
			(size 0.0762 0.0762)
			(layers "B.Cu" "B.Mask" "B.Paste")
			(net "GND")
			(options
				(clearance outline)
				(anchor circle)
			)
			(primitives
				(gr_poly
					(pts
						(arc
							(start 0.1524 0.127)
							(mid 0.137521 0.162921)
							(end 0.1016 0.1778)
						)
						(arc
							(start -0.1016 0.1778)
							(mid -0.137521 0.162921)
							(end -0.1524 0.127)
						)
						(arc
							(start -0.1524 -0.127)
							(mid -0.137521 -0.162921)
							(end -0.1016 -0.1778)
						)
						(arc
							(start 0.1016 -0.1778)
							(mid 0.137521 -0.162921)
							(end 0.1524 -0.127)
						)
					)
					(width 0)
					(fill yes)
				)
			)
		)
	)
	(footprint ""
		(layer "B.Cu")
		(at 127.970788 -56.5023 -90)
		(property "Reference" "C229"
			(at 0 0 90)
			(layer "B.SilkS")
			(hide yes)
			(effects
				(font
					(size 1.27 1.27)
				)
				(justify mirror)
			)
		)
		(property "Value" "SC1U6D3V1MX-GP"
			(at -1.9177 2.0193 270)
			(unlocked yes)
			(layer "B.Fab")
			(hide yes)
			(effects
				(font
					(size 1.016 1.016)
					(thickness 0.1524)
				)
				(justify mirror)
			)
		)
		(property "Device Type" "C0201H14"
			(at -1.9177 0.4953 270)
			(unlocked yes)
			(layer "B.Fab")
			(hide yes)
			(effects
				(font
					(size 1.016 1.016)
					(thickness 0.1524)
				)
				(justify mirror)
			)
		)
		(duplicate_pad_numbers_are_jumpers no)
		(fp_rect
			(start 0.1524 0.3048)
			(end -0.1524 -0.3048)
			(stroke
				(width 0)
				(type default)
			)
			(fill no)
			(layer "B.CrtYd")
		)
		(fp_poly
			(pts
				(xy 0.2794 0.6477) (xy 0.2794 -0.6477) (xy -0.2794 -0.6477) (xy -0.2794 -0.1905) (xy -0.1524 -0.1905)
				(xy -0.1524 -0.3048) (xy 0.1524 -0.3048) (xy 0.1524 0.3048) (xy -0.1524 0.3048) (xy -0.1524 -0.1778)
				(xy -0.2794 -0.1778) (xy -0.2794 0.6477)
			)
			(stroke
				(width 0)
				(type default)
			)
			(fill no)
			(layer "B.CrtYd")
		)
		(fp_rect
			(start 0.2794 0.6477)
			(end -0.2794 -0.6477)
			(stroke
				(width 0)
				(type default)
			)
			(fill no)
			(layer "B.Fab")
		)
		(pad "1" smd custom
			(at 0 -0.2794 90)
			(size 0.0762 0.0762)
			(layers "B.Cu" "B.Mask" "B.Paste")
			(net "GB_VDDA")
			(options
				(clearance outline)
				(anchor circle)
			)
			(primitives
				(gr_poly
					(pts
						(arc
							(start 0.1524 0.127)
							(mid 0.137521 0.162921)
							(end 0.1016 0.1778)
						)
						(arc
							(start -0.1016 0.1778)
							(mid -0.137521 0.162921)
							(end -0.1524 0.127)
						)
						(arc
							(start -0.1524 -0.127)
							(mid -0.137521 -0.162921)
							(end -0.1016 -0.1778)
						)
						(arc
							(start 0.1016 -0.1778)
							(mid 0.137521 -0.162921)
							(end 0.1524 -0.127)
						)
					)
					(width 0)
					(fill yes)
				)
			)
		)
		(pad "2" smd custom
			(at 0 0.2794 90)
			(size 0.0762 0.0762)
			(layers "B.Cu" "B.Mask" "B.Paste")
			(net "GND")
			(options
				(clearance outline)
				(anchor circle)
			)
			(primitives
				(gr_poly
					(pts
						(arc
							(start 0.1524 0.127)
							(mid 0.137521 0.162921)
							(end 0.1016 0.1778)
						)
						(arc
							(start -0.1016 0.1778)
							(mid -0.137521 0.162921)
							(end -0.1524 0.127)
						)
						(arc
							(start -0.1524 -0.127)
							(mid -0.137521 -0.162921)
							(end -0.1016 -0.1778)
						)
						(arc
							(start 0.1016 -0.1778)
							(mid 0.137521 -0.162921)
							(end 0.1524 -0.127)
						)
					)
					(width 0)
					(fill yes)
				)
			)
		)
	)
	(footprint ""
		(layer "B.Cu")
		(at 169.926 -62.992 180)
		(property "Reference" "C212"
			(at 0 0 0)
			(layer "B.SilkS")
			(hide yes)
			(effects
				(font
					(size 1.27 1.27)
				)
				(justify mirror)
			)
		)
		(property "Value" "SCD1U16V2KX-3GP"
			(at -1.1811 -2.7051 180)
			(unlocked yes)
			(layer "B.Fab")
			(hide yes)
			(effects
				(font
					(size 1.016 1.016)
					(thickness 0.1524)
				)
				(justify mirror)
			)
		)
		(property "Device Type" "C402H22"
			(at -1.1811 -4.2291 180)
			(unlocked yes)
			(layer "B.Fab")
			(hide yes)
			(effects
				(font
					(size 1.016 1.016)
					(thickness 0.1524)
				)
				(justify mirror)
			)
		)
		(duplicate_pad_numbers_are_jumpers no)
		(fp_rect
			(start 0.4318 0.9525)
			(end -0.4318 -0.9525)
			(stroke
				(width 0)
				(type default)
			)
			(fill no)
			(layer "B.CrtYd")
		)
		(fp_rect
			(start 0.4318 0.9525)
			(end -0.4318 -0.9525)
			(stroke
				(width 0)
				(type default)
			)
			(fill no)
			(layer "B.Fab")
		)
		(pad "1" smd custom
			(at 0 -0.4445)
			(size 0.1524 0.1524)
			(layers "B.Cu" "B.Mask" "B.Paste")
			(net "P3V3")
			(options
				(clearance outline)
				(anchor circle)
			)
			(primitives
				(gr_poly
					(pts
						(arc
							(start 0.3048 0.2032)
							(mid 0.275042 0.275042)
							(end 0.2032 0.3048)
						)
						(arc
							(start -0.2032 0.3048)
							(mid -0.275042 0.275042)
							(end -0.3048 0.2032)
						)
						(arc
							(start -0.3048 -0.2032)
							(mid -0.275042 -0.275042)
							(end -0.2032 -0.3048)
						)
						(arc
							(start 0.2032 -0.3048)
							(mid 0.275042 -0.275042)
							(end 0.3048 -0.2032)
						)
					)
					(width 0)
					(fill yes)
				)
			)
		)
		(pad "2" smd custom
			(at 0 0.4445)
			(size 0.1524 0.1524)
			(layers "B.Cu" "B.Mask" "B.Paste")
			(net "GND")
			(options
				(clearance outline)
				(anchor circle)
			)
			(primitives
				(gr_poly
					(pts
						(arc
							(start 0.3048 0.2032)
							(mid 0.275042 0.275042)
							(end 0.2032 0.3048)
						)
						(arc
							(start -0.2032 0.3048)
							(mid -0.275042 0.275042)
							(end -0.3048 0.2032)
						)
						(arc
							(start -0.3048 -0.2032)
							(mid -0.275042 -0.275042)
							(end -0.2032 -0.3048)
						)
						(arc
							(start 0.2032 -0.3048)
							(mid 0.275042 -0.275042)
							(end 0.3048 -0.2032)
						)
					)
					(width 0)
					(fill yes)
				)
			)
		)
	)
	(footprint ""
		(layer "B.Cu")
		(at 124.039376 -90.137742 90)
		(property "Reference" "R307"
			(at 0 0 90)
			(layer "B.SilkS")
			(hide yes)
			(effects
				(font
					(size 1.27 1.27)
				)
				(justify mirror)
			)
		)
		(property "Value" "10KR2F-2-GP"
			(at -0.064008 -3.993896 90)
			(unlocked yes)
			(layer "B.Fab")
			(hide yes)
			(effects
				(font
					(size 1.016 1.016)
					(thickness 0.1524)
				)
				(justify mirror)
			)
		)
		(property "Device Type" "R402H16"
			(at -0.064008 -5.517896 90)
			(unlocked yes)
			(layer "B.Fab")
			(hide yes)
			(effects
				(font
					(size 1.016 1.016)
					(thickness 0.1524)
				)
				(justify mirror)
			)
		)
		(duplicate_pad_numbers_are_jumpers no)
		(fp_line
			(start 0.508 -0.9398)
			(end 0.508 0.9398)
			(stroke
				(width 0.1524)
				(type default)
			)
			(layer "B.SilkS")
		)
		(fp_line
			(start -0.508 -0.9398)
			(end 0.508 -0.9398)
			(stroke
				(width 0.1524)
				(type default)
			)
			(layer "B.SilkS")
		)
		(fp_rect
			(start 0.508 0.9398)
			(end -0.508 -0.9398)
			(stroke
				(width 0)
				(type default)
			)
			(fill no)
			(layer "B.CrtYd")
		)
		(fp_rect
			(start 0.508 0.9398)
			(end -0.508 -0.9398)
			(stroke
				(width 0)
				(type default)
			)
			(fill no)
			(layer "B.Fab")
		)
		(pad "1" smd custom
			(at 0 -0.4445 270)
			(size 0.1397 0.1397)
			(layers "B.Cu" "B.Mask" "B.Paste")
			(net "BMC_SPARE_0_LS")
			(options
				(clearance outline)
				(anchor circle)
			)
			(primitives
				(gr_poly
					(pts
						(arc
							(start -0.1778 0.2794)
							(mid -0.249642 0.249642)
							(end -0.2794 0.1778)
						)
						(arc
							(start -0.2794 -0.1778)
							(mid -0.249642 -0.249642)
							(end -0.1778 -0.2794)
						)
						(arc
							(start 0.1778 -0.2794)
							(mid 0.249642 -0.249642)
							(end 0.2794 -0.1778)
						)
						(arc
							(start 0.2794 0.1778)
							(mid 0.249642 0.249642)
							(end 0.1778 0.2794)
						)
					)
					(width 0)
					(fill yes)
				)
			)
		)
		(pad "2" smd custom
			(at 0 0.4445 270)
			(size 0.1397 0.1397)
			(layers "B.Cu" "B.Mask" "B.Paste")
			(net "GND")
			(options
				(clearance outline)
				(anchor circle)
			)
			(primitives
				(gr_poly
					(pts
						(arc
							(start -0.1778 0.2794)
							(mid -0.249642 0.249642)
							(end -0.2794 0.1778)
						)
						(arc
							(start -0.2794 -0.1778)
							(mid -0.249642 -0.249642)
							(end -0.1778 -0.2794)
						)
						(arc
							(start 0.1778 -0.2794)
							(mid 0.249642 -0.249642)
							(end 0.2794 -0.1778)
						)
						(arc
							(start 0.2794 0.1778)
							(mid 0.249642 0.249642)
							(end 0.1778 0.2794)
						)
					)
					(width 0)
					(fill yes)
				)
			)
		)
	)
	(footprint ""
		(layer "B.Cu")
		(at 111.499904 -78.49997)
		(property "Reference" "TP49"
			(at 0 0 0)
			(layer "B.SilkS")
			(hide yes)
			(effects
				(font
					(size 1.27 1.27)
				)
				(justify mirror)
			)
		)
		(property "Value" "TPAD28-2-GP"
			(at 0.0127 -1.6637 0)
			(unlocked yes)
			(layer "B.Fab")
			(hide yes)
			(effects
				(font
					(size 1.016 1.016)
					(thickness 0.1524)
				)
				(justify mirror)
			)
		)
		(property "Device Type" "TPAD28"
			(at 0.0127 -3.1877 0)
			(unlocked yes)
			(layer "B.Fab")
			(hide yes)
			(effects
				(font
					(size 1.016 1.016)
					(thickness 0.1524)
				)
				(justify mirror)
			)
		)
		(duplicate_pad_numbers_are_jumpers no)
		(fp_poly
			(pts
				(arc
					(start 0.3556 0)
					(mid -0.3556 0)
					(end 0.3556 0)
				)
			)
			(stroke
				(width 0)
				(type default)
			)
			(fill no)
			(layer "B.CrtYd")
		)
		(fp_poly
			(pts
				(arc
					(start 0.6096 0)
					(mid -0.6096 0)
					(end 0.6096 0)
				)
			)
			(stroke
				(width 0)
				(type default)
			)
			(fill no)
			(layer "B.Fab")
		)
		(pad "1" smd circle
			(at 0 0 180)
			(size 0.7112 0.7112)
			(layers "B.Cu" "B.Mask" "B.Paste")
			(net "XM_GP_CS_1#_TP")
		)
	)
	(footprint ""
		(layer "B.Cu")
		(at 137.4648 -72.9996 -90)
		(property "Reference" "C11"
			(at 0 0 90)
			(layer "B.SilkS")
			(hide yes)
			(effects
				(font
					(size 1.27 1.27)
				)
				(justify mirror)
			)
		)
		(property "Value" "SCD01U16V1KX-GP"
			(at 2.8321 -1.7399 270)
			(unlocked yes)
			(layer "B.Fab")
			(hide yes)
			(effects
				(font
					(size 1.016 1.016)
					(thickness 0.1524)
				)
				(justify mirror)
			)
		)
		(property "Device Type" "C0201H13"
			(at 2.8321 -3.2639 270)
			(unlocked yes)
			(layer "B.Fab")
			(hide yes)
			(effects
				(font
					(size 1.016 1.016)
					(thickness 0.1524)
				)
				(justify mirror)
			)
		)
		(duplicate_pad_numbers_are_jumpers no)
		(fp_rect
			(start 0.2794 0.6477)
			(end -0.2794 -0.6477)
			(stroke
				(width 0)
				(type default)
			)
			(fill no)
			(layer "B.CrtYd")
		)
		(fp_rect
			(start 0.2794 0.6477)
			(end -0.2794 -0.6477)
			(stroke
				(width 0)
				(type default)
			)
			(fill no)
			(layer "B.Fab")
		)
		(pad "1" smd custom
			(at 0 -0.2794 90)
			(size 0.0762 0.0762)
			(layers "B.Cu" "B.Mask" "B.Paste")
			(net "PHY_DPB_TO_SCC_6_DP")
			(options
				(clearance outline)
				(anchor circle)
			)
			(primitives
				(gr_poly
					(pts
						(arc
							(start 0.1524 0.127)
							(mid 0.137521 0.162921)
							(end 0.1016 0.1778)
						)
						(arc
							(start -0.1016 0.1778)
							(mid -0.137521 0.162921)
							(end -0.1524 0.127)
						)
						(arc
							(start -0.1524 -0.127)
							(mid -0.137521 -0.162921)
							(end -0.1016 -0.1778)
						)
						(arc
							(start 0.1016 -0.1778)
							(mid 0.137521 -0.162921)
							(end 0.1524 -0.127)
						)
					)
					(width 0)
					(fill yes)
				)
			)
		)
		(pad "2" smd custom
			(at 0 0.2794 90)
			(size 0.0762 0.0762)
			(layers "B.Cu" "B.Mask" "B.Paste")
			(net "PHY_DPB_TO_SCC_C_6_DP")
			(options
				(clearance outline)
				(anchor circle)
			)
			(primitives
				(gr_poly
					(pts
						(arc
							(start 0.1524 0.127)
							(mid 0.137521 0.162921)
							(end 0.1016 0.1778)
						)
						(arc
							(start -0.1016 0.1778)
							(mid -0.137521 0.162921)
							(end -0.1524 0.127)
						)
						(arc
							(start -0.1524 -0.127)
							(mid -0.137521 -0.162921)
							(end -0.1016 -0.1778)
						)
						(arc
							(start 0.1016 -0.1778)
							(mid 0.137521 -0.162921)
							(end 0.1524 -0.127)
						)
					)
					(width 0)
					(fill yes)
				)
			)
		)
	)
)
